# S9S_MB_2U (Grand Teton) — schematic netlist excerpt (pin names and nets, part order shuffled) for the footprints in the layout excerpt that follows; sources: Cadence DE-HDL packaged netlist, KiCad conversion of 03242023_DA0F0TMBIJ0_F0T_Motherboard_J_brd_V01_OCP.brd

R3996  Q_RES  0 5% CHIP  pkg 0402LF  page 242 : A = VIRTUAL_RESEAT_FPGA_N ; B = P12V_SCM_EN
R3282  Q_RES  68K 1% EMPTY  pkg 0402LF  page 166 : A = FM_P2E_EQB0 ; B = GND

(kicad_pcb
	(version 20260206)
	(generator "pcbnew")
	(generator_version "10.0")
	(general
		(thickness 1.6)
		(legacy_teardrops no)
	)
	(paper "A4")
	(title_block
		(title "03242023_DA0F0TMBIJ0_F0T_Motherboard_J_brd_V01_OCP.brd")
		(comment 1 "Grand Teton / footprints 146-147 of 6105")
	)
	(layers
		(0 "F.Cu" signal "TOP")
		(4 "In1.Cu" signal "GND")
		(6 "In2.Cu" signal "IN1")
		(8 "In3.Cu" signal "GND1")
		(10 "In4.Cu" signal "IN2")
		(12 "In5.Cu" signal "GND2")
		(14 "In6.Cu" signal "IN3")
		(16 "In7.Cu" signal "GND3")
		(18 "In8.Cu" signal "VCC")
		(20 "In9.Cu" signal "VCC1")
		(22 "In10.Cu" signal "GND4")
		(24 "In11.Cu" signal "IN4")
		(26 "In12.Cu" signal "GND5")
		(28 "In13.Cu" signal "IN5")
		(30 "In14.Cu" signal "GND6")
		(32 "In15.Cu" signal "IN6")
		(34 "In16.Cu" signal "GND7")
		(2 "B.Cu" signal "BOTTOM")
		(9 "F.Adhes" user "F.Adhesive")
		(11 "B.Adhes" user "B.Adhesive")
		(13 "F.Paste" user "Package Geometry/Pastemask Top")
		(15 "B.Paste" user "Package Geometry/Pastemask Bottom")
		(5 "F.SilkS" user "Ref Des/Silkscreen Top")
		(7 "B.SilkS" user "Ref Des/Silkscreen Bottom")
		(1 "F.Mask" user "Board Geometry/Soldermask Top")
		(3 "B.Mask" user "Board Geometry/Soldermask Bottom")
		(17 "Dwgs.User" user "User.Drawings")
		(19 "Cmts.User" user "User.Comments")
		(21 "Eco1.User" user "User.Eco1")
		(23 "Eco2.User" user "User.Eco2")
		(25 "Edge.Cuts" user "Board Geometry/Outline")
		(27 "Margin" user)
		(31 "F.CrtYd" user "Package Geometry/Place Bound Top")
		(29 "B.CrtYd" user "Package Geometry/Place Bound Bottom")
		(35 "F.Fab" user "Ref Des/Assembly Top")
		(33 "B.Fab" user "Ref Des/Assembly Bottom")
	)
	(footprint ""
		(layer "F.Cu")
		(at 24.447754 -399.532094 90)
		(property "Reference" "R3282"
			(at 0 0 90)
			(layer "F.SilkS")
			(hide yes)
			(effects
				(font
					(size 1.27 1.27)
				)
			)
		)
		(property "Value" ""
			(at 0 0 90)
			(layer "F.Fab")
			(effects
				(font
					(size 1.27 1.27)
				)
			)
		)
		(duplicate_pad_numbers_are_jumpers no)
		(fp_line
			(start 0.7874 -0.4064)
			(end 0.7874 0.4064)
			(stroke
				(width 0.1524)
				(type default)
			)
			(layer "F.SilkS")
		)
		(fp_line
			(start -0.7874 -0.4064)
			(end 0.7874 -0.4064)
			(stroke
				(width 0.1524)
				(type default)
			)
			(layer "F.SilkS")
		)
		(fp_line
			(start 0.7874 0.4064)
			(end -0.7874 0.4064)
			(stroke
				(width 0.1524)
				(type default)
			)
			(layer "F.SilkS")
		)
		(fp_line
			(start -0.7874 0.4064)
			(end -0.7874 -0.4064)
			(stroke
				(width 0.1524)
				(type default)
			)
			(layer "F.SilkS")
		)
		(fp_line
			(start -0.12065 -0.305054)
			(end -0.12065 -0.2794)
			(stroke
				(width 0.1)
				(type default)
			)
			(layer "F.Fab")
		)
		(fp_line
			(start -0.67945 -0.305054)
			(end -0.12065 -0.305054)
			(stroke
				(width 0.1)
				(type default)
			)
			(layer "F.Fab")
		)
		(fp_line
			(start 0.67945 -0.3048)
			(end 0.67945 0.3048)
			(stroke
				(width 0.1)
				(type default)
			)
			(layer "F.Fab")
		)
		(fp_line
			(start 0.12065 -0.3048)
			(end 0.67945 -0.3048)
			(stroke
				(width 0.1)
				(type default)
			)
			(layer "F.Fab")
		)
		(fp_line
			(start 0.12065 -0.2794)
			(end 0.12065 -0.3048)
			(stroke
				(width 0.1)
				(type default)
			)
			(layer "F.Fab")
		)
		(fp_line
			(start -0.12065 -0.2794)
			(end 0.12065 -0.2794)
			(stroke
				(width 0.1)
				(type default)
			)
			(layer "F.Fab")
		)
		(fp_line
			(start 0.120396 0.2794)
			(end -0.12065 0.2794)
			(stroke
				(width 0.1)
				(type default)
			)
			(layer "F.Fab")
		)
		(fp_line
			(start -0.12065 0.2794)
			(end -0.12065 0.3048)
			(stroke
				(width 0.1)
				(type default)
			)
			(layer "F.Fab")
		)
		(fp_line
			(start 0.67945 0.3048)
			(end 0.120396 0.3048)
			(stroke
				(width 0.1)
				(type default)
			)
			(layer "F.Fab")
		)
		(fp_line
			(start 0.120396 0.3048)
			(end 0.120396 0.2794)
			(stroke
				(width 0.1)
				(type default)
			)
			(layer "F.Fab")
		)
		(fp_line
			(start -0.12065 0.3048)
			(end -0.67945 0.3048)
			(stroke
				(width 0.1)
				(type default)
			)
			(layer "F.Fab")
		)
		(fp_line
			(start -0.67945 0.3048)
			(end -0.67945 -0.305054)
			(stroke
				(width 0.1)
				(type default)
			)
			(layer "F.Fab")
		)
		(pad "1" smd circle
			(at -0.40005 0 90)
			(size 0 0)
			(layers "F.Cu" "F.Mask" "F.Paste")
			(net "FM_P2E_EQB0")
		)
		(pad "2" smd circle
			(at 0.40005 0 90)
			(size 0 0)
			(layers "F.Cu" "F.Mask" "F.Paste")
			(net "GND")
		)
	)
	(footprint ""
		(layer "F.Cu")
		(at 197.177406 -40.138604)
		(property "Reference" "R3996"
			(at 0 0 0)
			(layer "F.SilkS")
			(hide yes)
			(effects
				(font
					(size 1.27 1.27)
				)
			)
		)
		(property "Value" ""
			(at 0 0 0)
			(layer "F.Fab")
			(effects
				(font
					(size 1.27 1.27)
				)
			)
		)
		(duplicate_pad_numbers_are_jumpers no)
		(fp_line
			(start -0.7874 -0.4064)
			(end 0.7874 -0.4064)
			(stroke
				(width 0.1524)
				(type default)
			)
			(layer "F.SilkS")
		)
		(fp_line
			(start -0.7874 0.4064)
			(end -0.7874 -0.4064)
			(stroke
				(width 0.1524)
				(type default)
			)
			(layer "F.SilkS")
		)
		(fp_line
			(start 0.7874 -0.4064)
			(end 0.7874 0.4064)
			(stroke
				(width 0.1524)
				(type default)
			)
			(layer "F.SilkS")
		)
		(fp_line
			(start 0.7874 0.4064)
			(end -0.7874 0.4064)
			(stroke
				(width 0.1524)
				(type default)
			)
			(layer "F.SilkS")
		)
		(fp_line
			(start -0.67945 -0.305054)
			(end -0.12065 -0.305054)
			(stroke
				(width 0.1)
				(type default)
			)
			(layer "F.Fab")
		)
		(fp_line
			(start -0.67945 0.3048)
			(end -0.67945 -0.305054)
			(stroke
				(width 0.1)
				(type default)
			)
			(layer "F.Fab")
		)
		(fp_line
			(start -0.12065 -0.305054)
			(end -0.12065 -0.2794)
			(stroke
				(width 0.1)
				(type default)
			)
			(layer "F.Fab")
		)
		(fp_line
			(start -0.12065 -0.2794)
			(end 0.12065 -0.2794)
			(stroke
				(width 0.1)
				(type default)
			)
			(layer "F.Fab")
		)
		(fp_line
			(start -0.12065 0.2794)
			(end -0.12065 0.3048)
			(stroke
				(width 0.1)
				(type default)
			)
			(layer "F.Fab")
		)
		(fp_line
			(start -0.12065 0.3048)
			(end -0.67945 0.3048)
			(stroke
				(width 0.1)
				(type default)
			)
			(layer "F.Fab")
		)
		(fp_line
			(start 0.120396 0.2794)
			(end -0.12065 0.2794)
			(stroke
				(width 0.1)
				(type default)
			)
			(layer "F.Fab")
		)
		(fp_line
			(start 0.120396 0.3048)
			(end 0.120396 0.2794)
			(stroke
				(width 0.1)
				(type default)
			)
			(layer "F.Fab")
		)
		(fp_line
			(start 0.12065 -0.3048)
			(end 0.67945 -0.3048)
			(stroke
				(width 0.1)
				(type default)
			)
			(layer "F.Fab")
		)
		(fp_line
			(start 0.12065 -0.2794)
			(end 0.12065 -0.3048)
			(stroke
				(width 0.1)
				(type default)
			)
			(layer "F.Fab")
		)
		(fp_line
			(start 0.67945 -0.3048)
			(end 0.67945 0.3048)
			(stroke
				(width 0.1)
				(type default)
			)
			(layer "F.Fab")
		)
		(fp_line
			(start 0.67945 0.3048)
			(end 0.120396 0.3048)
			(stroke
				(width 0.1)
				(type default)
			)
			(layer "F.Fab")
		)
		(pad "1" smd circle
			(at -0.40005 0)
			(size 0 0)
			(layers "F.Cu" "F.Mask" "F.Paste")
			(net "VIRTUAL_RESEAT_FPGA_N")
		)
		(pad "2" smd circle
			(at 0.40005 0)
			(size 0 0)
			(layers "F.Cu" "F.Mask" "F.Paste")
			(net "P12V_SCM_EN")
		)
	)
)
